# SCM (Grand Teton) — schematic netlist excerpt (pin names and nets, part order shuffled) for the footprints in the layout excerpt that follows; sources: Cadence DE-HDL packaged netlist, KiCad conversion of 12092022_DA0F0TMDCD0_F0T_Management_Board_D_brd_V3_OCP.brd

C67  Q_CAP  1UF 25V 10% X6S  pkg C0402  page 16 : A = P1V2_STBY_MVDD_CK ; B = GND
R369  Q_RES  120 1% CHIP  pkg 0402LF  page 20 : A = M_BMC_DDR4_MACT_N ; B = P1V2_AUX

(kicad_pcb
	(version 20260206)
	(generator "pcbnew")
	(generator_version "10.0")
	(general
		(thickness 1.6)
		(legacy_teardrops no)
	)
	(paper "A4")
	(title_block
		(title "12092022_DA0F0TMDCD0_F0T_Management_Board_D_brd_V3_OCP.brd")
		(comment 1 "Grand Teton / footprints 891-892 of 1440")
	)
	(layers
		(0 "F.Cu" signal "TOP")
		(4 "In1.Cu" signal "GND")
		(6 "In2.Cu" signal "IN1")
		(8 "In3.Cu" signal "GND1")
		(10 "In4.Cu" signal "IN2")
		(12 "In5.Cu" signal "VCC")
		(14 "In6.Cu" signal "VCC1")
		(16 "In7.Cu" signal "IN3")
		(18 "In8.Cu" signal "GND2")
		(20 "In9.Cu" signal "IN4")
		(22 "In10.Cu" signal "GND3")
		(2 "B.Cu" signal "BOTTOM")
		(9 "F.Adhes" user "F.Adhesive")
		(11 "B.Adhes" user "B.Adhesive")
		(13 "F.Paste" user "Package Geometry/Pastemask Top")
		(15 "B.Paste" user "Package Geometry/Pastemask Bottom")
		(5 "F.SilkS" user "Ref Des/Silkscreen Top")
		(7 "B.SilkS" user "Ref Des/Silkscreen Bottom")
		(1 "F.Mask" user "Board Geometry/Soldermask Top")
		(3 "B.Mask" user "Board Geometry/Soldermask Bottom")
		(17 "Dwgs.User" user "User.Drawings")
		(19 "Cmts.User" user "User.Comments")
		(21 "Eco1.User" user "User.Eco1")
		(23 "Eco2.User" user "User.Eco2")
		(25 "Edge.Cuts" user "Board Geometry/Outline")
		(27 "Margin" user)
		(31 "F.CrtYd" user "Package Geometry/Place Bound Top")
		(29 "B.CrtYd" user "Package Geometry/Place Bound Bottom")
		(35 "F.Fab" user "Ref Des/Assembly Top")
		(33 "B.Fab" user "Ref Des/Assembly Bottom")
	)
	(footprint ""
		(layer "B.Cu")
		(at 67.029838 -40.87622 90)
		(property "Reference" "C67"
			(at 0 0 90)
			(layer "B.SilkS")
			(hide yes)
			(effects
				(font
					(size 1.27 1.27)
				)
				(justify mirror)
			)
		)
		(property "Value" ""
			(at 0 0 90)
			(layer "B.Fab")
			(effects
				(font
					(size 1.27 1.27)
				)
				(justify mirror)
			)
		)
		(duplicate_pad_numbers_are_jumpers no)
		(fp_line
			(start 0.7874 -0.4064)
			(end -0.7874 -0.4064)
			(stroke
				(width 0.1524)
				(type default)
			)
			(layer "B.SilkS")
		)
		(fp_line
			(start -0.7874 -0.4064)
			(end -0.7874 0.4064)
			(stroke
				(width 0.1524)
				(type default)
			)
			(layer "B.SilkS")
		)
		(fp_line
			(start 0.7874 0.4064)
			(end 0.7874 -0.4064)
			(stroke
				(width 0.1524)
				(type default)
			)
			(layer "B.SilkS")
		)
		(fp_line
			(start -0.7874 0.4064)
			(end 0.7874 0.4064)
			(stroke
				(width 0.1524)
				(type default)
			)
			(layer "B.SilkS")
		)
		(fp_line
			(start 0.67945 -0.305054)
			(end 0.12065 -0.305054)
			(stroke
				(width 0.1)
				(type default)
			)
			(layer "B.Fab")
		)
		(fp_line
			(start 0.12065 -0.305054)
			(end 0.12065 -0.2794)
			(stroke
				(width 0.1)
				(type default)
			)
			(layer "B.Fab")
		)
		(fp_line
			(start -0.12065 -0.3048)
			(end -0.67945 -0.3048)
			(stroke
				(width 0.1)
				(type default)
			)
			(layer "B.Fab")
		)
		(fp_line
			(start -0.67945 -0.3048)
			(end -0.67945 0.3048)
			(stroke
				(width 0.1)
				(type default)
			)
			(layer "B.Fab")
		)
		(fp_line
			(start 0.12065 -0.2794)
			(end -0.12065 -0.2794)
			(stroke
				(width 0.1)
				(type default)
			)
			(layer "B.Fab")
		)
		(fp_line
			(start -0.12065 -0.2794)
			(end -0.12065 -0.3048)
			(stroke
				(width 0.1)
				(type default)
			)
			(layer "B.Fab")
		)
		(fp_line
			(start 0.12065 0.2794)
			(end 0.12065 0.3048)
			(stroke
				(width 0.1)
				(type default)
			)
			(layer "B.Fab")
		)
		(fp_line
			(start -0.120396 0.2794)
			(end 0.12065 0.2794)
			(stroke
				(width 0.1)
				(type default)
			)
			(layer "B.Fab")
		)
		(fp_line
			(start 0.67945 0.3048)
			(end 0.67945 -0.305054)
			(stroke
				(width 0.1)
				(type default)
			)
			(layer "B.Fab")
		)
		(fp_line
			(start 0.12065 0.3048)
			(end 0.67945 0.3048)
			(stroke
				(width 0.1)
				(type default)
			)
			(layer "B.Fab")
		)
		(fp_line
			(start -0.120396 0.3048)
			(end -0.120396 0.2794)
			(stroke
				(width 0.1)
				(type default)
			)
			(layer "B.Fab")
		)
		(fp_line
			(start -0.67945 0.3048)
			(end -0.120396 0.3048)
			(stroke
				(width 0.1)
				(type default)
			)
			(layer "B.Fab")
		)
		(pad "1" smd circle
			(at 0.40005 0 270)
			(size 0 0)
			(layers "B.Cu" "B.Mask" "B.Paste")
			(net "P1V2_STBY_MVDD_CK")
		)
		(pad "2" smd circle
			(at -0.40005 0 270)
			(size 0 0)
			(layers "B.Cu" "B.Mask" "B.Paste")
			(net "GND")
		)
	)
	(footprint ""
		(layer "B.Cu")
		(at 83.16722 -41.506394 180)
		(property "Reference" "R369"
			(at 0 0 0)
			(layer "B.SilkS")
			(hide yes)
			(effects
				(font
					(size 1.27 1.27)
				)
				(justify mirror)
			)
		)
		(property "Value" ""
			(at 0 0 0)
			(layer "B.Fab")
			(effects
				(font
					(size 1.27 1.27)
				)
				(justify mirror)
			)
		)
		(duplicate_pad_numbers_are_jumpers no)
		(fp_line
			(start 0.7874 0.4064)
			(end 0.7874 -0.4064)
			(stroke
				(width 0.1524)
				(type default)
			)
			(layer "B.SilkS")
		)
		(fp_line
			(start 0.7874 -0.4064)
			(end -0.7874 -0.4064)
			(stroke
				(width 0.1524)
				(type default)
			)
			(layer "B.SilkS")
		)
		(fp_line
			(start -0.7874 0.4064)
			(end 0.7874 0.4064)
			(stroke
				(width 0.1524)
				(type default)
			)
			(layer "B.SilkS")
		)
		(fp_line
			(start -0.7874 -0.4064)
			(end -0.7874 0.4064)
			(stroke
				(width 0.1524)
				(type default)
			)
			(layer "B.SilkS")
		)
		(fp_line
			(start 0.67945 0.3048)
			(end 0.67945 -0.305054)
			(stroke
				(width 0.1)
				(type default)
			)
			(layer "B.Fab")
		)
		(fp_line
			(start 0.67945 -0.305054)
			(end 0.12065 -0.305054)
			(stroke
				(width 0.1)
				(type default)
			)
			(layer "B.Fab")
		)
		(fp_line
			(start 0.12065 0.3048)
			(end 0.67945 0.3048)
			(stroke
				(width 0.1)
				(type default)
			)
			(layer "B.Fab")
		)
		(fp_line
			(start 0.12065 0.2794)
			(end 0.12065 0.3048)
			(stroke
				(width 0.1)
				(type default)
			)
			(layer "B.Fab")
		)
		(fp_line
			(start 0.12065 -0.2794)
			(end -0.12065 -0.2794)
			(stroke
				(width 0.1)
				(type default)
			)
			(layer "B.Fab")
		)
		(fp_line
			(start 0.12065 -0.305054)
			(end 0.12065 -0.2794)
			(stroke
				(width 0.1)
				(type default)
			)
			(layer "B.Fab")
		)
		(fp_line
			(start -0.120396 0.3048)
			(end -0.120396 0.2794)
			(stroke
				(width 0.1)
				(type default)
			)
			(layer "B.Fab")
		)
		(fp_line
			(start -0.120396 0.2794)
			(end 0.12065 0.2794)
			(stroke
				(width 0.1)
				(type default)
			)
			(layer "B.Fab")
		)
		(fp_line
			(start -0.12065 -0.2794)
			(end -0.12065 -0.3048)
			(stroke
				(width 0.1)
				(type default)
			)
			(layer "B.Fab")
		)
		(fp_line
			(start -0.12065 -0.3048)
			(end -0.67945 -0.3048)
			(stroke
				(width 0.1)
				(type default)
			)
			(layer "B.Fab")
		)
		(fp_line
			(start -0.67945 0.3048)
			(end -0.120396 0.3048)
			(stroke
				(width 0.1)
				(type default)
			)
			(layer "B.Fab")
		)
		(fp_line
			(start -0.67945 -0.3048)
			(end -0.67945 0.3048)
			(stroke
				(width 0.1)
				(type default)
			)
			(layer "B.Fab")
		)
		(pad "1" smd circle
			(at 0.40005 0)
			(size 0 0)
			(layers "B.Cu" "B.Mask" "B.Paste")
			(net "M_BMC_DDR4_MACT_N")
		)
		(pad "2" smd circle
			(at -0.40005 0)
			(size 0 0)
			(layers "B.Cu" "B.Mask" "B.Paste")
			(net "P1V2_AUX")
		)
	)
)
